FILE_TYPE=LIBRARY_PARTS;
primitive 'PI3PCIE3212ZBEX';
  pin
    'VDD2':
      PIN_NUMBER='(10)';
      PINUSE='POWER';
      NO_LOAD_CHECK='Both';
      NO_IO_CHECK='Both';
      NO_ASSERT_CHECK='TRUE';
      NO_DIR_CHECK='TRUE';
      ALLOW_CONNECT='TRUE';
    'VDD1':
      PIN_NUMBER='(6)';
      PINUSE='POWER';
      NO_LOAD_CHECK='Both';
      NO_IO_CHECK='Both';
      NO_ASSERT_CHECK='TRUE';
      NO_DIR_CHECK='TRUE';
      ALLOW_CONNECT='TRUE';
    'VDD0':
      PIN_NUMBER='(1)';
      PINUSE='POWER';
      NO_LOAD_CHECK='Both';
      NO_IO_CHECK='Both';
      NO_ASSERT_CHECK='TRUE';
      NO_DIR_CHECK='TRUE';
      ALLOW_CONNECT='TRUE';
    'A0_P':
      PIN_NUMBER='(3)';
      BIDIRECTIONAL='TRUE';
      INPUT_LOAD='(-0.01,0.01)';
      OUTPUT_LOAD='(1.0,-1.0)';
    '-A0':
      PIN_NUMBER='(4)';
      BIDIRECTIONAL='TRUE';
      INPUT_LOAD='(-0.01,0.01)';
      OUTPUT_LOAD='(1.0,-1.0)';
    'A1_P':
      PIN_NUMBER='(7)';
      BIDIRECTIONAL='TRUE';
      INPUT_LOAD='(-0.01,0.01)';
      OUTPUT_LOAD='(1.0,-1.0)';
    '-A1':
      PIN_NUMBER='(8)';
      BIDIRECTIONAL='TRUE';
      INPUT_LOAD='(-0.01,0.01)';
      OUTPUT_LOAD='(1.0,-1.0)';
    'SEL':
      PIN_NUMBER='(9)';
      INPUT_LOAD='(-0.01,0.01)';
    'B0_P':
      PIN_NUMBER='(19)';
      BIDIRECTIONAL='TRUE';
      INPUT_LOAD='(-0.01,0.01)';
      OUTPUT_LOAD='(1.0,-1.0)';
    '-B0':
      PIN_NUMBER='(18)';
      BIDIRECTIONAL='TRUE';
      INPUT_LOAD='(-0.01,0.01)';
      OUTPUT_LOAD='(1.0,-1.0)';
    'B1_P':
      PIN_NUMBER='(17)';
      BIDIRECTIONAL='TRUE';
      INPUT_LOAD='(-0.01,0.01)';
      OUTPUT_LOAD='(1.0,-1.0)';
    '-B1':
      PIN_NUMBER='(16)';
      BIDIRECTIONAL='TRUE';
      INPUT_LOAD='(-0.01,0.01)';
      OUTPUT_LOAD='(1.0,-1.0)';
    'C0_P':
      PIN_NUMBER='(15)';
      BIDIRECTIONAL='TRUE';
      INPUT_LOAD='(-0.01,0.01)';
      OUTPUT_LOAD='(1.0,-1.0)';
    '-C0':
      PIN_NUMBER='(14)';
      BIDIRECTIONAL='TRUE';
      INPUT_LOAD='(-0.01,0.01)';
      OUTPUT_LOAD='(1.0,-1.0)';
    'C1_P':
      PIN_NUMBER='(13)';
      BIDIRECTIONAL='TRUE';
      INPUT_LOAD='(-0.01,0.01)';
      OUTPUT_LOAD='(1.0,-1.0)';
    '-C1':
      PIN_NUMBER='(12)';
      BIDIRECTIONAL='TRUE';
      INPUT_LOAD='(-0.01,0.01)';
      OUTPUT_LOAD='(1.0,-1.0)';
    'TH':
      PIN_NUMBER='(TH)';
      PINUSE='POWER';
      NO_LOAD_CHECK='Both';
      NO_IO_CHECK='Both';
      NO_ASSERT_CHECK='TRUE';
      NO_DIR_CHECK='TRUE';
      ALLOW_CONNECT='TRUE';
    'GND2':
      PIN_NUMBER='(11)';
      PINUSE='POWER';
      NO_LOAD_CHECK='Both';
      NO_IO_CHECK='Both';
      NO_ASSERT_CHECK='TRUE';
      NO_DIR_CHECK='TRUE';
      ALLOW_CONNECT='TRUE';
    'GND1':
      PIN_NUMBER='(5)';
      PINUSE='POWER';
      NO_LOAD_CHECK='Both';
      NO_IO_CHECK='Both';
      NO_ASSERT_CHECK='TRUE';
      NO_DIR_CHECK='TRUE';
      ALLOW_CONNECT='TRUE';
    'GND0':
      PIN_NUMBER='(20)';
      PINUSE='POWER';
      NO_LOAD_CHECK='Both';
      NO_IO_CHECK='Both';
      NO_ASSERT_CHECK='TRUE';
      NO_DIR_CHECK='TRUE';
      ALLOW_CONNECT='TRUE';
    'PD':
      PIN_NUMBER='(2)';
      INPUT_LOAD='(-0.01,0.01)';
  end_pin;
  body
    PART_NAME='PI3PCIE3212ZBEX';
    BODY_NAME='PI3PCIE3212ZBEX';
    PHYS_DES_PREFIX='U';
    CLASS='IC';
  end_body;
end_primitive;

END.
